(kicad_pcb
	(version 20260206)
	(generator "pcbnew")
	(generator_version "10.0")
	(general
		(thickness 1.6)
		(legacy_teardrops no)
	)
	(paper "A4")
	(title_block
		(title "Bryce Canyon_F.DPB_16315-1-OCP.brd")
		(comment 1 "Bryce Canyon / footprints 1216-1223 of 2223")
	)
	(layers
		(0 "F.Cu" signal "TOP")
		(4 "In1.Cu" signal "L2GND")
		(6 "In2.Cu" signal "L3")
		(8 "In3.Cu" signal "L4GND")
		(10 "In4.Cu" signal "L5")
		(12 "In5.Cu" signal "L6VCC")
		(14 "In6.Cu" signal "L7VCC")
		(16 "In7.Cu" signal "L8")
		(18 "In8.Cu" signal "L9GND")
		(20 "In9.Cu" signal "L10")
		(22 "In10.Cu" signal "L11GND")
		(2 "B.Cu" signal "BOTTOM")
		(9 "F.Adhes" user "F.Adhesive")
		(11 "B.Adhes" user "B.Adhesive")
		(13 "F.Paste" user "Package Geometry/Pastemask Top")
		(15 "B.Paste" user "Package Geometry/Pastemask Bottom")
		(5 "F.SilkS" user "Ref Des/Silkscreen Top")
		(7 "B.SilkS" user "Ref Des/Silkscreen Bottom")
		(1 "F.Mask" user "Board Geometry/Soldermask Top")
		(3 "B.Mask" user "Board Geometry/Soldermask Bottom")
		(17 "Dwgs.User" user "User.Drawings")
		(19 "Cmts.User" user "User.Comments")
		(21 "Eco1.User" user "User.Eco1")
		(23 "Eco2.User" user "User.Eco2")
		(25 "Edge.Cuts" user "Board Geometry/Outline")
		(27 "Margin" user)
		(31 "F.CrtYd" user "Package Geometry/Place Bound Top")
		(29 "B.CrtYd" user "Package Geometry/Place Bound Bottom")
		(35 "F.Fab" user "Ref Des/Assembly Top")
		(33 "B.Fab" user "Ref Des/Assembly Bottom")
	)
	(footprint ""
		(layer "F.Cu")
		(at 318.77 -61.127894 -90)
		(property "Reference" "C432"
			(at 0 0 270)
			(layer "F.SilkS")
			(hide yes)
			(effects
				(font
					(size 1.27 1.27)
				)
			)
		)
		(property "Value" "SCD01U50V2KX-1GP"
			(at 1.1811 -2.7051 270)
			(unlocked yes)
			(layer "F.Fab")
			(hide yes)
			(effects
				(font
					(size 1.016 1.016)
					(thickness 0.1524)
				)
			)
		)
		(property "Device Type" "C402H22"
			(at 1.1811 -4.2291 270)
			(unlocked yes)
			(layer "F.Fab")
			(hide yes)
			(effects
				(font
					(size 1.016 1.016)
					(thickness 0.1524)
				)
			)
		)
		(duplicate_pad_numbers_are_jumpers no)
		(fp_rect
			(start -0.4318 0.9525)
			(end 0.4318 -0.9525)
			(stroke
				(width 0)
				(type default)
			)
			(fill no)
			(layer "F.CrtYd")
		)
		(fp_rect
			(start -0.4318 0.9525)
			(end 0.4318 -0.9525)
			(stroke
				(width 0)
				(type default)
			)
			(fill no)
			(layer "F.Fab")
		)
		(pad "1" smd custom
			(at 0 -0.4445 270)
			(size 0.1524 0.1524)
			(layers "F.Cu" "F.Mask" "F.Paste")
			(net "HDD_PRSNT_30")
			(options
				(clearance outline)
				(anchor circle)
			)
			(primitives
				(gr_poly
					(pts
						(arc
							(start 0.3048 -0.2032)
							(mid 0.275042 -0.275042)
							(end 0.2032 -0.3048)
						)
						(arc
							(start -0.2032 -0.3048)
							(mid -0.275042 -0.275042)
							(end -0.3048 -0.2032)
						)
						(arc
							(start -0.3048 0.2032)
							(mid -0.275042 0.275042)
							(end -0.2032 0.3048)
						)
						(arc
							(start 0.2032 0.3048)
							(mid 0.275042 0.275042)
							(end 0.3048 0.2032)
						)
					)
					(width 0)
					(fill yes)
				)
			)
		)
		(pad "2" smd custom
			(at 0 0.4445 270)
			(size 0.1524 0.1524)
			(layers "F.Cu" "F.Mask" "F.Paste")
			(net "GND")
			(options
				(clearance outline)
				(anchor circle)
			)
			(primitives
				(gr_poly
					(pts
						(arc
							(start 0.3048 -0.2032)
							(mid 0.275042 -0.275042)
							(end 0.2032 -0.3048)
						)
						(arc
							(start -0.2032 -0.3048)
							(mid -0.275042 -0.275042)
							(end -0.3048 -0.2032)
						)
						(arc
							(start -0.3048 0.2032)
							(mid -0.275042 0.275042)
							(end -0.2032 0.3048)
						)
						(arc
							(start 0.2032 0.3048)
							(mid 0.275042 0.275042)
							(end 0.3048 0.2032)
						)
					)
					(width 0)
					(fill yes)
				)
			)
		)
	)
	(footprint ""
		(layer "F.Cu")
		(at 366.174274 -146.66341 180)
		(property "Reference" "R1103"
			(at 0 0 180)
			(layer "F.SilkS")
			(hide yes)
			(effects
				(font
					(size 1.27 1.27)
				)
			)
		)
		(property "Value" "0R5J-5-GP"
			(at 0 -8.9535 180)
			(unlocked yes)
			(layer "F.Fab")
			(hide yes)
			(effects
				(font
					(size 1.27 1.016)
					(thickness 0.1524)
				)
			)
		)
		(property "Device Type" "R805H24"
			(at 0 -10.6299 180)
			(unlocked yes)
			(layer "F.Fab")
			(hide yes)
			(effects
				(font
					(size 1.27 1.016)
					(thickness 0.1524)
				)
			)
		)
		(duplicate_pad_numbers_are_jumpers no)
		(fp_line
			(start 0.889 1.7018)
			(end 0.889 -0.508)
			(stroke
				(width 0.1524)
				(type default)
			)
			(layer "F.SilkS")
		)
		(fp_line
			(start 0.889 -1.7018)
			(end 0.889 -0.381)
			(stroke
				(width 0.1524)
				(type default)
			)
			(layer "F.SilkS")
		)
		(fp_line
			(start 0.889 -1.7018)
			(end -0.889 -1.7018)
			(stroke
				(width 0.1524)
				(type default)
			)
			(layer "F.SilkS")
		)
		(fp_line
			(start -0.889 1.7018)
			(end 0.889 1.7018)
			(stroke
				(width 0.1524)
				(type default)
			)
			(layer "F.SilkS")
		)
		(fp_line
			(start -0.889 0.0762)
			(end -0.889 1.7018)
			(stroke
				(width 0.1524)
				(type default)
			)
			(layer "F.SilkS")
		)
		(fp_line
			(start -0.889 -1.7018)
			(end -0.889 0.2794)
			(stroke
				(width 0.1524)
				(type default)
			)
			(layer "F.SilkS")
		)
		(fp_poly
			(pts
				(xy 0.9652 -1.778) (xy 0.9652 1.778) (xy -0.9652 1.778) (xy -0.9652 -1.778)
			)
			(stroke
				(width 0)
				(type default)
			)
			(fill no)
			(layer "F.CrtYd")
		)
		(fp_rect
			(start -0.9652 1.778)
			(end 0.9652 -1.778)
			(stroke
				(width 0)
				(type default)
			)
			(fill no)
			(layer "F.Fab")
		)
		(pad "1" smd rect
			(at 0 -0.9652 180)
			(size 1.397 1.143)
			(layers "F.Cu" "F.Mask" "F.Paste")
			(net "MB1_CM_GATE")
		)
		(pad "2" smd rect
			(at 0 0.9652 180)
			(size 1.397 1.143)
			(layers "F.Cu" "F.Mask" "F.Paste")
			(net "MB1_CM_GATE_R")
		)
	)
	(footprint ""
		(layer "F.Cu")
		(at 35.617912 -245.55069 -90)
		(property "Reference" "C607"
			(at 0 0 270)
			(layer "F.SilkS")
			(hide yes)
			(effects
				(font
					(size 1.27 1.27)
				)
			)
		)
		(property "Value" "SC2200P50V2KX-2GP"
			(at 1.1811 -2.7051 270)
			(unlocked yes)
			(layer "F.Fab")
			(hide yes)
			(effects
				(font
					(size 1.016 1.016)
					(thickness 0.1524)
				)
			)
		)
		(property "Device Type" "C402H22"
			(at 1.1811 -4.2291 270)
			(unlocked yes)
			(layer "F.Fab")
			(hide yes)
			(effects
				(font
					(size 1.016 1.016)
					(thickness 0.1524)
				)
			)
		)
		(duplicate_pad_numbers_are_jumpers no)
		(fp_rect
			(start -0.4318 0.9525)
			(end 0.4318 -0.9525)
			(stroke
				(width 0)
				(type default)
			)
			(fill no)
			(layer "F.CrtYd")
		)
		(fp_rect
			(start -0.4318 0.9525)
			(end 0.4318 -0.9525)
			(stroke
				(width 0)
				(type default)
			)
			(fill no)
			(layer "F.Fab")
		)
		(pad "1" smd custom
			(at 0 -0.4445 270)
			(size 0.1524 0.1524)
			(layers "F.Cu" "F.Mask" "F.Paste")
			(net "P5V_A_LL")
			(options
				(clearance outline)
				(anchor circle)
			)
			(primitives
				(gr_poly
					(pts
						(arc
							(start 0.3048 -0.2032)
							(mid 0.275042 -0.275042)
							(end 0.2032 -0.3048)
						)
						(arc
							(start -0.2032 -0.3048)
							(mid -0.275042 -0.275042)
							(end -0.3048 -0.2032)
						)
						(arc
							(start -0.3048 0.2032)
							(mid -0.275042 0.275042)
							(end -0.2032 0.3048)
						)
						(arc
							(start 0.2032 0.3048)
							(mid 0.275042 0.275042)
							(end 0.3048 0.2032)
						)
					)
					(width 0)
					(fill yes)
				)
			)
		)
		(pad "2" smd custom
			(at 0 0.4445 270)
			(size 0.1524 0.1524)
			(layers "F.Cu" "F.Mask" "F.Paste")
			(net "P5V_SNB")
			(options
				(clearance outline)
				(anchor circle)
			)
			(primitives
				(gr_poly
					(pts
						(arc
							(start 0.3048 -0.2032)
							(mid 0.275042 -0.275042)
							(end 0.2032 -0.3048)
						)
						(arc
							(start -0.2032 -0.3048)
							(mid -0.275042 -0.275042)
							(end -0.3048 -0.2032)
						)
						(arc
							(start -0.3048 0.2032)
							(mid -0.275042 0.275042)
							(end -0.2032 0.3048)
						)
						(arc
							(start 0.2032 0.3048)
							(mid 0.275042 0.275042)
							(end 0.3048 0.2032)
						)
					)
					(width 0)
					(fill yes)
				)
			)
		)
	)
	(footprint ""
		(layer "F.Cu")
		(at 95.608902 -47.749968 -90)
		(property "Reference" "VIA68"
			(at 0 0 270)
			(layer "F.SilkS")
			(hide yes)
			(effects
				(font
					(size 1.27 1.27)
				)
			)
		)
		(property "Value" "100OHM-8L-1D6MM-L18L16-GP"
			(at -3.7211 -4.5085 270)
			(unlocked yes)
			(layer "F.Fab")
			(hide yes)
			(effects
				(font
					(size 1.016 1.016)
					(thickness 0.1524)
				)
			)
		)
		(property "Device Type" "VIA-PCIE-4P-394076"
			(at -3.7211 -6.0325 270)
			(unlocked yes)
			(layer "F.Fab")
			(hide yes)
			(effects
				(font
					(size 1.016 1.016)
					(thickness 0.1524)
				)
			)
		)
		(duplicate_pad_numbers_are_jumpers no)
		(fp_rect
			(start -1.9685 0.381)
			(end 1.9685 -0.381)
			(stroke
				(width 0)
				(type default)
			)
			(fill no)
			(layer "F.CrtYd")
		)
		(fp_rect
			(start -1.9685 0.381)
			(end 1.9685 -0.381)
			(stroke
				(width 0)
				(type default)
			)
			(fill no)
			(layer "F.Fab")
		)
		(pad "1" thru_hole circle
			(at -1.5875 0 270)
			(size 0.508 0.508)
			(drill 0.254)
			(layers "*.Cu" "*.Mask")
			(remove_unused_layers no)
			(net "GND")
			(clearance 0.127)
			(thermal_gap 0.127)
		)
		(pad "2" thru_hole circle
			(at -0.5715 0 270)
			(size 0.508 0.508)
			(drill 0.254)
			(layers "*.Cu" "*.Mask")
			(remove_unused_layers no)
			(net "PHY_DRV_A_TO_SCC_A_26_DP")
			(clearance 0.127)
			(thermal_gap 0.127)
		)
		(pad "3" thru_hole circle
			(at 0.5715 0 270)
			(size 0.508 0.508)
			(drill 0.254)
			(layers "*.Cu" "*.Mask")
			(remove_unused_layers no)
			(net "PHY_DRV_A_TO_SCC_A_26_DN")
			(clearance 0.127)
			(thermal_gap 0.127)
		)
		(pad "4" thru_hole circle
			(at 1.5875 0 270)
			(size 0.508 0.508)
			(drill 0.254)
			(layers "*.Cu" "*.Mask")
			(remove_unused_layers no)
			(net "GND")
			(clearance 0.127)
			(thermal_gap 0.127)
		)
	)
	(footprint ""
		(layer "F.Cu")
		(at 464.2739 -164.443918 90)
		(property "Reference" "R652"
			(at 0 0 90)
			(layer "F.SilkS")
			(hide yes)
			(effects
				(font
					(size 1.27 1.27)
				)
			)
		)
		(property "Value" "200KR2F-L-GP"
			(at 0.064008 -3.993896 90)
			(unlocked yes)
			(layer "F.Fab")
			(hide yes)
			(effects
				(font
					(size 1.016 1.016)
					(thickness 0.1524)
				)
			)
		)
		(property "Device Type" "R402H16"
			(at 0.064008 -5.517896 90)
			(unlocked yes)
			(layer "F.Fab")
			(hide yes)
			(effects
				(font
					(size 1.016 1.016)
					(thickness 0.1524)
				)
			)
		)
		(duplicate_pad_numbers_are_jumpers no)
		(fp_line
			(start 0.508 -0.9398)
			(end -0.508 -0.9398)
			(stroke
				(width 0.1524)
				(type default)
			)
			(layer "F.SilkS")
		)
		(fp_line
			(start -0.508 -0.9398)
			(end -0.508 0.9398)
			(stroke
				(width 0.1524)
				(type default)
			)
			(layer "F.SilkS")
		)
		(fp_rect
			(start -0.508 0.9398)
			(end 0.508 -0.9398)
			(stroke
				(width 0)
				(type default)
			)
			(fill no)
			(layer "F.CrtYd")
		)
		(fp_rect
			(start -0.508 0.9398)
			(end 0.508 -0.9398)
			(stroke
				(width 0)
				(type default)
			)
			(fill no)
			(layer "F.Fab")
		)
		(pad "1" smd custom
			(at 0 -0.4445 90)
			(size 0.1397 0.1397)
			(layers "F.Cu" "F.Mask" "F.Paste")
			(net "SW_HDD_R22")
			(options
				(clearance outline)
				(anchor circle)
			)
			(primitives
				(gr_poly
					(pts
						(arc
							(start -0.1778 -0.2794)
							(mid -0.249642 -0.249642)
							(end -0.2794 -0.1778)
						)
						(arc
							(start -0.2794 0.1778)
							(mid -0.249642 0.249642)
							(end -0.1778 0.2794)
						)
						(arc
							(start 0.1778 0.2794)
							(mid 0.249642 0.249642)
							(end 0.2794 0.1778)
						)
						(arc
							(start 0.2794 -0.1778)
							(mid 0.249642 -0.249642)
							(end 0.1778 -0.2794)
						)
					)
					(width 0)
					(fill yes)
				)
			)
		)
		(pad "2" smd custom
			(at 0 0.4445 90)
			(size 0.1397 0.1397)
			(layers "F.Cu" "F.Mask" "F.Paste")
			(net "SW_HDD_N22")
			(options
				(clearance outline)
				(anchor circle)
			)
			(primitives
				(gr_poly
					(pts
						(arc
							(start -0.1778 -0.2794)
							(mid -0.249642 -0.249642)
							(end -0.2794 -0.1778)
						)
						(arc
							(start -0.2794 0.1778)
							(mid -0.249642 0.249642)
							(end -0.1778 0.2794)
						)
						(arc
							(start 0.1778 0.2794)
							(mid 0.249642 0.249642)
							(end 0.2794 0.1778)
						)
						(arc
							(start 0.2794 -0.1778)
							(mid 0.249642 -0.249642)
							(end 0.1778 -0.2794)
						)
					)
					(width 0)
					(fill yes)
				)
			)
		)
	)
	(footprint ""
		(layer "F.Cu")
		(at 378.249942 -209.399886)
		(property "Reference" "FLED9"
			(at 0 0 0)
			(layer "F.SilkS")
			(hide yes)
			(effects
				(font
					(size 1.27 1.27)
				)
			)
		)
		(property "Value" "LED-BY-19-GP"
			(at -2.132076 1.414018 0)
			(unlocked yes)
			(layer "F.Fab")
			(hide yes)
			(effects
				(font
					(size 1.016 1.016)
					(thickness 0.1524)
				)
			)
		)
		(property "Device Type" "LED-1615-4PH26"
			(at -2.132076 -0.109982 0)
			(unlocked yes)
			(layer "F.Fab")
			(hide yes)
			(effects
				(font
					(size 1.016 1.016)
					(thickness 0.1524)
				)
			)
		)
		(duplicate_pad_numbers_are_jumpers no)
		(fp_line
			(start -1.2954 0.254)
			(end -1.2954 1.6002)
			(stroke
				(width 0.508)
				(type default)
			)
			(layer "F.SilkS")
		)
		(fp_line
			(start -1.2954 1.6002)
			(end 1.2954 1.6002)
			(stroke
				(width 0.508)
				(type default)
			)
			(layer "F.SilkS")
		)
		(fp_line
			(start -1.1176 -1.4224)
			(end 1.1176 -1.4224)
			(stroke
				(width 0.1524)
				(type default)
			)
			(layer "F.SilkS")
		)
		(fp_line
			(start -1.1176 1.4224)
			(end -1.1176 -1.4224)
			(stroke
				(width 0.1524)
				(type default)
			)
			(layer "F.SilkS")
		)
		(fp_line
			(start 1.1176 -1.4224)
			(end 1.1176 1.4224)
			(stroke
				(width 0.1524)
				(type default)
			)
			(layer "F.SilkS")
		)
		(fp_line
			(start 1.1176 1.4224)
			(end -1.1176 1.4224)
			(stroke
				(width 0.1524)
				(type default)
			)
			(layer "F.SilkS")
		)
		(fp_line
			(start 1.2954 1.6002)
			(end 1.2954 0.254)
			(stroke
				(width 0.508)
				(type default)
			)
			(layer "F.SilkS")
		)
		(fp_rect
			(start -0.7493 0.8001)
			(end 0.7493 -0.8001)
			(stroke
				(width 0)
				(type default)
			)
			(fill no)
			(layer "F.CrtYd")
		)
		(fp_poly
			(pts
				(xy -1.3716 1.6764) (xy -1.3716 -1.6764) (xy 1.3716 -1.6764) (xy 1.3716 0.0635) (xy 0.7493 0.0635)
				(xy 0.7493 -0.8001) (xy -0.7493 -0.8001) (xy -0.7493 0.8001) (xy 0.7493 0.8001) (xy 0.7493 0.0762)
				(xy 1.3716 0.0762) (xy 1.3716 1.6764)
			)
			(stroke
				(width 0)
				(type default)
			)
			(fill no)
			(layer "F.CrtYd")
		)
		(fp_rect
			(start -1.3716 1.6764)
			(end 1.3716 -1.6764)
			(stroke
				(width 0)
				(type default)
			)
			(fill no)
			(layer "F.Fab")
		)
		(pad "1" smd rect
			(at 0.50038 -0.73025)
			(size 0.7112 0.8636)
			(layers "F.Cu" "F.Mask" "F.Paste")
			(net "DRV_ACT_8")
		)
		(pad "2" smd rect
			(at -0.50038 -0.73025)
			(size 0.7112 0.8636)
			(layers "F.Cu" "F.Mask" "F.Paste")
			(net "FLT_HDD8")
		)
		(pad "3" smd rect
			(at 0.50038 0.73025)
			(size 0.7112 0.8636)
			(layers "F.Cu" "F.Mask" "F.Paste")
			(net "DRV_ACT_8_N")
		)
		(pad "4" smd rect
			(at -0.50038 0.73025)
			(size 0.7112 0.8636)
			(layers "F.Cu" "F.Mask" "F.Paste")
			(net "FLT_HDD8_N")
		)
	)
	(footprint ""
		(layer "F.Cu")
		(at 127.15875 -162.749992 -90)
		(property "Reference" "VIA52"
			(at 0 0 270)
			(layer "F.SilkS")
			(hide yes)
			(effects
				(font
					(size 1.27 1.27)
				)
			)
		)
		(property "Value" "100OHM-8L-1D6MM-L18L16-GP"
			(at -3.7211 -4.5085 270)
			(unlocked yes)
			(layer "F.Fab")
			(hide yes)
			(effects
				(font
					(size 1.016 1.016)
					(thickness 0.1524)
				)
			)
		)
		(property "Device Type" "VIA-PCIE-4P-394076"
			(at -3.7211 -6.0325 270)
			(unlocked yes)
			(layer "F.Fab")
			(hide yes)
			(effects
				(font
					(size 1.016 1.016)
					(thickness 0.1524)
				)
			)
		)
		(duplicate_pad_numbers_are_jumpers no)
		(fp_rect
			(start -1.9685 0.381)
			(end 1.9685 -0.381)
			(stroke
				(width 0)
				(type default)
			)
			(fill no)
			(layer "F.CrtYd")
		)
		(fp_rect
			(start -1.9685 0.381)
			(end 1.9685 -0.381)
			(stroke
				(width 0)
				(type default)
			)
			(fill no)
			(layer "F.Fab")
		)
		(pad "1" thru_hole circle
			(at -1.5875 0 270)
			(size 0.508 0.508)
			(drill 0.254)
			(layers "*.Cu" "*.Mask")
			(remove_unused_layers no)
			(net "GND")
			(clearance 0.127)
			(thermal_gap 0.127)
		)
		(pad "2" thru_hole circle
			(at -0.5715 0 270)
			(size 0.508 0.508)
			(drill 0.254)
			(layers "*.Cu" "*.Mask")
			(remove_unused_layers no)
			(net "PHY_DRV_A_TO_SCC_A_15_DP")
			(clearance 0.127)
			(thermal_gap 0.127)
		)
		(pad "3" thru_hole circle
			(at 0.5715 0 270)
			(size 0.508 0.508)
			(drill 0.254)
			(layers "*.Cu" "*.Mask")
			(remove_unused_layers no)
			(net "PHY_DRV_A_TO_SCC_A_15_DN")
			(clearance 0.127)
			(thermal_gap 0.127)
		)
		(pad "4" thru_hole circle
			(at 1.5875 0 270)
			(size 0.508 0.508)
			(drill 0.254)
			(layers "*.Cu" "*.Mask")
			(remove_unused_layers no)
			(net "GND")
			(clearance 0.127)
			(thermal_gap 0.127)
		)
	)
	(footprint ""
		(layer "F.Cu")
		(at 177.8 -176.000918 -90)
		(property "Reference" "C262"
			(at 0 0 270)
			(layer "F.SilkS")
			(hide yes)
			(effects
				(font
					(size 1.27 1.27)
				)
			)
		)
		(property "Value" "SC10U16V6KX-2GP"
			(at -0.0762 -5.1308 270)
			(unlocked yes)
			(layer "F.Fab")
			(hide yes)
			(effects
				(font
					(size 1.016 1.016)
					(thickness 0.1524)
				)
			)
		)
		(property "Device Type" "C1206H71"
			(at -0.127 -6.6548 270)
			(unlocked yes)
			(layer "F.Fab")
			(hide yes)
			(effects
				(font
					(size 1.016 1.016)
					(thickness 0.1524)
				)
			)
		)
		(duplicate_pad_numbers_are_jumpers no)
		(fp_line
			(start -1.016 2.2352)
			(end -1.016 0.8382)
			(stroke
				(width 0.1524)
				(type default)
			)
			(layer "F.SilkS")
		)
		(fp_line
			(start 1.016 2.2352)
			(end -1.016 2.2352)
			(stroke
				(width 0.1524)
				(type default)
			)
			(layer "F.SilkS")
		)
		(fp_line
			(start 1.016 0.8382)
			(end 1.016 2.2352)
			(stroke
				(width 0.1524)
				(type default)
			)
			(layer "F.SilkS")
		)
		(fp_line
			(start -1.016 -0.8382)
			(end -1.016 -2.2352)
			(stroke
				(width 0.1524)
				(type default)
			)
			(layer "F.SilkS")
		)
		(fp_line
			(start -1.016 -2.2352)
			(end 1.016 -2.2352)
			(stroke
				(width 0.1524)
				(type default)
			)
			(layer "F.SilkS")
		)
		(fp_line
			(start 1.016 -2.2352)
			(end 1.016 -0.8382)
			(stroke
				(width 0.1524)
				(type default)
			)
			(layer "F.SilkS")
		)
		(fp_rect
			(start -1.0922 2.3114)
			(end 1.0922 -2.3114)
			(stroke
				(width 0)
				(type default)
			)
			(fill no)
			(layer "F.CrtYd")
		)
		(fp_poly
			(pts
				(xy 1.0922 -2.3114) (xy 1.0922 2.3114) (xy -1.0922 2.3114) (xy -1.0922 -2.3114)
			)
			(stroke
				(width 0)
				(type default)
			)
			(fill no)
			(layer "F.Fab")
		)
		(pad "1" smd rect
			(at 0 -1.397 270)
			(size 1.651 1.27)
			(layers "F.Cu" "F.Mask" "F.Paste")
			(net "P5V_HDD17")
		)
		(pad "2" smd rect
			(at 0 1.397 270)
			(size 1.651 1.27)
			(layers "F.Cu" "F.Mask" "F.Paste")
			(net "GND")
		)
	)
)
